(kicad_pcb
	(version 20260206)
	(generator "pcbnew")
	(generator_version "10.0")
	(general
		(thickness 1.6)
		(legacy_teardrops no)
	)
	(paper "A4")
	(title_block
		(title "baseboard — 13948-1b.1110WZS1818.brd")
		(comment 1 "Honey Badger (Wiwynn) / footprints 1886-1894 of 2523")
	)
	(layers
		(0 "F.Cu" signal "TOP")
		(4 "In1.Cu" signal "L2GND")
		(6 "In2.Cu" signal "L3")
		(8 "In3.Cu" signal "L4VCC")
		(10 "In4.Cu" signal "L5VCC")
		(12 "In5.Cu" signal "L6")
		(14 "In6.Cu" signal "L7GND")
		(2 "B.Cu" signal "BOTTOM")
		(9 "F.Adhes" user "F.Adhesive")
		(11 "B.Adhes" user "B.Adhesive")
		(13 "F.Paste" user "Package Geometry/Pastemask Top")
		(15 "B.Paste" user "Package Geometry/Pastemask Bottom")
		(5 "F.SilkS" user "Ref Des/Silkscreen Top")
		(7 "B.SilkS" user "Ref Des/Silkscreen Bottom")
		(1 "F.Mask" user "Board Geometry/Soldermask Top")
		(3 "B.Mask" user "Board Geometry/Soldermask Bottom")
		(17 "Dwgs.User" user "User.Drawings")
		(19 "Cmts.User" user "User.Comments")
		(21 "Eco1.User" user "User.Eco1")
		(23 "Eco2.User" user "User.Eco2")
		(25 "Edge.Cuts" user "Board Geometry/Outline")
		(27 "Margin" user)
		(31 "F.CrtYd" user "Package Geometry/Place Bound Top")
		(29 "B.CrtYd" user "Package Geometry/Place Bound Bottom")
		(35 "F.Fab" user "Ref Des/Assembly Top")
		(33 "B.Fab" user "Ref Des/Assembly Bottom")
	)
	(footprint ""
		(layer "B.Cu")
		(at 300.9519 -182.91048)
		(property "Reference" "TP112"
			(at 0 0 0)
			(layer "B.SilkS")
			(hide yes)
			(effects
				(font
					(size 1.27 1.27)
				)
				(justify mirror)
			)
		)
		(property "Value" "TPAD28"
			(at -0.0127 -1.8034 0)
			(unlocked yes)
			(layer "B.Fab")
			(hide yes)
			(effects
				(font
					(size 1.016 1.016)
					(thickness 0.1524)
				)
				(justify mirror)
			)
		)
		(property "Device Type" "TPAD28"
			(at -0.0127 -3.3274 0)
			(unlocked yes)
			(layer "B.Fab")
			(hide yes)
			(effects
				(font
					(size 1.016 1.016)
					(thickness 0.1524)
				)
				(justify mirror)
			)
		)
		(duplicate_pad_numbers_are_jumpers no)
		(fp_poly
			(pts
				(arc
					(start 0.3556 0)
					(mid -0.3556 0)
					(end 0.3556 0)
				)
			)
			(stroke
				(width 0)
				(type default)
			)
			(fill no)
			(layer "B.CrtYd")
		)
		(fp_poly
			(pts
				(arc
					(start 0.6096 0)
					(mid -0.6096 0)
					(end 0.6096 0)
				)
			)
			(stroke
				(width 0)
				(type default)
			)
			(fill no)
			(layer "B.Fab")
		)
		(pad "1" smd circle
			(at 0 0 180)
			(size 0.7112 0.7112)
			(layers "B.Cu" "B.Mask" "B.Paste")
			(net "TP_BMC_GPIOM4")
		)
	)
	(footprint ""
		(layer "B.Cu")
		(at 295.9862 -203.962 180)
		(property "Reference" "C181"
			(at 0 0 0)
			(layer "B.SilkS")
			(hide yes)
			(effects
				(font
					(size 1.27 1.27)
				)
				(justify mirror)
			)
		)
		(property "Value" "SCD1U16V2KX-3GP"
			(at -1.1811 -2.7051 180)
			(unlocked yes)
			(layer "B.Fab")
			(hide yes)
			(effects
				(font
					(size 1.016 1.016)
					(thickness 0.1524)
				)
				(justify mirror)
			)
		)
		(property "Device Type" "C402H22"
			(at -1.1811 -4.2291 180)
			(unlocked yes)
			(layer "B.Fab")
			(hide yes)
			(effects
				(font
					(size 1.016 1.016)
					(thickness 0.1524)
				)
				(justify mirror)
			)
		)
		(duplicate_pad_numbers_are_jumpers no)
		(fp_rect
			(start 0.4318 0.9525)
			(end -0.4318 -0.9525)
			(stroke
				(width 0)
				(type default)
			)
			(fill no)
			(layer "B.CrtYd")
		)
		(fp_rect
			(start 0.4318 0.9525)
			(end -0.4318 -0.9525)
			(stroke
				(width 0)
				(type default)
			)
			(fill no)
			(layer "B.Fab")
		)
		(pad "1" smd custom
			(at 0 -0.4445)
			(size 0.1524 0.1524)
			(layers "B.Cu" "B.Mask" "B.Paste")
			(net "P1V53_STBY")
			(options
				(clearance outline)
				(anchor circle)
			)
			(primitives
				(gr_poly
					(pts
						(arc
							(start 0.3048 0.2032)
							(mid 0.275042 0.275042)
							(end 0.2032 0.3048)
						)
						(arc
							(start -0.2032 0.3048)
							(mid -0.275042 0.275042)
							(end -0.3048 0.2032)
						)
						(arc
							(start -0.3048 -0.2032)
							(mid -0.275042 -0.275042)
							(end -0.2032 -0.3048)
						)
						(arc
							(start 0.2032 -0.3048)
							(mid 0.275042 -0.275042)
							(end 0.3048 -0.2032)
						)
					)
					(width 0)
					(fill yes)
				)
			)
		)
		(pad "2" smd custom
			(at 0 0.4445)
			(size 0.1524 0.1524)
			(layers "B.Cu" "B.Mask" "B.Paste")
			(net "GND")
			(options
				(clearance outline)
				(anchor circle)
			)
			(primitives
				(gr_poly
					(pts
						(arc
							(start 0.3048 0.2032)
							(mid 0.275042 0.275042)
							(end 0.2032 0.3048)
						)
						(arc
							(start -0.2032 0.3048)
							(mid -0.275042 0.275042)
							(end -0.3048 0.2032)
						)
						(arc
							(start -0.3048 -0.2032)
							(mid -0.275042 -0.275042)
							(end -0.2032 -0.3048)
						)
						(arc
							(start 0.2032 -0.3048)
							(mid 0.275042 -0.275042)
							(end 0.3048 -0.2032)
						)
					)
					(width 0)
					(fill yes)
				)
			)
		)
	)
	(footprint ""
		(layer "B.Cu")
		(at 83.82 -21.844)
		(property "Reference" "PR187"
			(at 0 0 0)
			(layer "B.SilkS")
			(hide yes)
			(effects
				(font
					(size 1.27 1.27)
				)
				(justify mirror)
			)
		)
		(property "Value" "100KR2F-L1-GP"
			(at -0.064008 -3.993896 0)
			(unlocked yes)
			(layer "B.Fab")
			(hide yes)
			(effects
				(font
					(size 1.016 1.016)
					(thickness 0.1524)
				)
				(justify mirror)
			)
		)
		(property "Device Type" "R402H16"
			(at -0.064008 -5.517896 0)
			(unlocked yes)
			(layer "B.Fab")
			(hide yes)
			(effects
				(font
					(size 1.016 1.016)
					(thickness 0.1524)
				)
				(justify mirror)
			)
		)
		(duplicate_pad_numbers_are_jumpers no)
		(fp_line
			(start -0.508 -0.9398)
			(end 0.508 -0.9398)
			(stroke
				(width 0.1524)
				(type default)
			)
			(layer "B.SilkS")
		)
		(fp_line
			(start 0.508 -0.9398)
			(end 0.508 0.9398)
			(stroke
				(width 0.1524)
				(type default)
			)
			(layer "B.SilkS")
		)
		(fp_rect
			(start 0.508 0.9398)
			(end -0.508 -0.9398)
			(stroke
				(width 0)
				(type default)
			)
			(fill no)
			(layer "B.CrtYd")
		)
		(fp_rect
			(start 0.508 0.9398)
			(end -0.508 -0.9398)
			(stroke
				(width 0)
				(type default)
			)
			(fill no)
			(layer "B.Fab")
		)
		(pad "1" smd custom
			(at 0 -0.4445 180)
			(size 0.1397 0.1397)
			(layers "B.Cu" "B.Mask" "B.Paste")
			(net "VT235_VDES")
			(options
				(clearance outline)
				(anchor circle)
			)
			(primitives
				(gr_poly
					(pts
						(arc
							(start -0.1778 0.2794)
							(mid -0.249642 0.249642)
							(end -0.2794 0.1778)
						)
						(arc
							(start -0.2794 -0.1778)
							(mid -0.249642 -0.249642)
							(end -0.1778 -0.2794)
						)
						(arc
							(start 0.1778 -0.2794)
							(mid 0.249642 -0.249642)
							(end 0.2794 -0.1778)
						)
						(arc
							(start 0.2794 0.1778)
							(mid 0.249642 0.249642)
							(end 0.1778 0.2794)
						)
					)
					(width 0)
					(fill yes)
				)
			)
		)
		(pad "2" smd custom
			(at 0 0.4445 180)
			(size 0.1397 0.1397)
			(layers "B.Cu" "B.Mask" "B.Paste")
			(net "AVSO_VREF")
			(options
				(clearance outline)
				(anchor circle)
			)
			(primitives
				(gr_poly
					(pts
						(arc
							(start -0.1778 0.2794)
							(mid -0.249642 0.249642)
							(end -0.2794 0.1778)
						)
						(arc
							(start -0.2794 -0.1778)
							(mid -0.249642 -0.249642)
							(end -0.1778 -0.2794)
						)
						(arc
							(start 0.1778 -0.2794)
							(mid 0.249642 -0.249642)
							(end 0.2794 -0.1778)
						)
						(arc
							(start 0.2794 0.1778)
							(mid 0.249642 0.249642)
							(end 0.1778 0.2794)
						)
					)
					(width 0)
					(fill yes)
				)
			)
		)
	)
	(footprint ""
		(layer "B.Cu")
		(at 158.42996 -109.474254 90)
		(property "Reference" "SC1245"
			(at 0 0 90)
			(layer "B.SilkS")
			(hide yes)
			(effects
				(font
					(size 1.27 1.27)
				)
				(justify mirror)
			)
		)
		(property "Value" "SCD1U6D3V1KX-GP"
			(at 2.8321 -1.7399 90)
			(unlocked yes)
			(layer "B.Fab")
			(hide yes)
			(effects
				(font
					(size 1.016 1.016)
					(thickness 0.1524)
				)
				(justify mirror)
			)
		)
		(property "Device Type" "C0201H13"
			(at 2.8321 -3.2639 90)
			(unlocked yes)
			(layer "B.Fab")
			(hide yes)
			(effects
				(font
					(size 1.016 1.016)
					(thickness 0.1524)
				)
				(justify mirror)
			)
		)
		(duplicate_pad_numbers_are_jumpers no)
		(fp_rect
			(start 0.2794 0.6477)
			(end -0.2794 -0.6477)
			(stroke
				(width 0)
				(type default)
			)
			(fill no)
			(layer "B.CrtYd")
		)
		(fp_rect
			(start 0.2794 0.6477)
			(end -0.2794 -0.6477)
			(stroke
				(width 0)
				(type default)
			)
			(fill no)
			(layer "B.Fab")
		)
		(pad "1" smd custom
			(at 0 -0.2794 270)
			(size 0.0762 0.0762)
			(layers "B.Cu" "B.Mask" "B.Paste")
			(net "P0V9_E")
			(options
				(clearance outline)
				(anchor circle)
			)
			(primitives
				(gr_poly
					(pts
						(arc
							(start 0.1524 0.127)
							(mid 0.137521 0.162921)
							(end 0.1016 0.1778)
						)
						(arc
							(start -0.1016 0.1778)
							(mid -0.137521 0.162921)
							(end -0.1524 0.127)
						)
						(arc
							(start -0.1524 -0.127)
							(mid -0.137521 -0.162921)
							(end -0.1016 -0.1778)
						)
						(arc
							(start 0.1016 -0.1778)
							(mid 0.137521 -0.162921)
							(end 0.1524 -0.127)
						)
					)
					(width 0)
					(fill yes)
				)
			)
		)
		(pad "2" smd custom
			(at 0 0.2794 270)
			(size 0.0762 0.0762)
			(layers "B.Cu" "B.Mask" "B.Paste")
			(net "GND")
			(options
				(clearance outline)
				(anchor circle)
			)
			(primitives
				(gr_poly
					(pts
						(arc
							(start 0.1524 0.127)
							(mid 0.137521 0.162921)
							(end 0.1016 0.1778)
						)
						(arc
							(start -0.1016 0.1778)
							(mid -0.137521 0.162921)
							(end -0.1524 0.127)
						)
						(arc
							(start -0.1524 -0.127)
							(mid -0.137521 -0.162921)
							(end -0.1016 -0.1778)
						)
						(arc
							(start 0.1016 -0.1778)
							(mid 0.137521 -0.162921)
							(end 0.1524 -0.127)
						)
					)
					(width 0)
					(fill yes)
				)
			)
		)
	)
	(footprint ""
		(layer "B.Cu")
		(at 53.28793 -76.761086)
		(property "Reference" "SC1280"
			(at 0 0 0)
			(layer "B.SilkS")
			(hide yes)
			(effects
				(font
					(size 1.27 1.27)
				)
				(justify mirror)
			)
		)
		(property "Value" "SCD01U50V2KX-1GP"
			(at -1.1811 -2.7051 0)
			(unlocked yes)
			(layer "B.Fab")
			(hide yes)
			(effects
				(font
					(size 1.016 1.016)
					(thickness 0.1524)
				)
				(justify mirror)
			)
		)
		(property "Device Type" "C402H22"
			(at -1.1811 -4.2291 0)
			(unlocked yes)
			(layer "B.Fab")
			(hide yes)
			(effects
				(font
					(size 1.016 1.016)
					(thickness 0.1524)
				)
				(justify mirror)
			)
		)
		(duplicate_pad_numbers_are_jumpers no)
		(fp_rect
			(start 0.4318 0.9525)
			(end -0.4318 -0.9525)
			(stroke
				(width 0)
				(type default)
			)
			(fill no)
			(layer "B.CrtYd")
		)
		(fp_rect
			(start 0.4318 0.9525)
			(end -0.4318 -0.9525)
			(stroke
				(width 0)
				(type default)
			)
			(fill no)
			(layer "B.Fab")
		)
		(pad "1" smd custom
			(at 0 -0.4445 180)
			(size 0.1524 0.1524)
			(layers "B.Cu" "B.Mask" "B.Paste")
			(net "SAS_EXP2CONN_RX_P_23")
			(options
				(clearance outline)
				(anchor circle)
			)
			(primitives
				(gr_poly
					(pts
						(arc
							(start 0.3048 0.2032)
							(mid 0.275042 0.275042)
							(end 0.2032 0.3048)
						)
						(arc
							(start -0.2032 0.3048)
							(mid -0.275042 0.275042)
							(end -0.3048 0.2032)
						)
						(arc
							(start -0.3048 -0.2032)
							(mid -0.275042 -0.275042)
							(end -0.2032 -0.3048)
						)
						(arc
							(start 0.2032 -0.3048)
							(mid 0.275042 -0.275042)
							(end 0.3048 -0.2032)
						)
					)
					(width 0)
					(fill yes)
				)
			)
		)
		(pad "2" smd custom
			(at 0 0.4445 180)
			(size 0.1524 0.1524)
			(layers "B.Cu" "B.Mask" "B.Paste")
			(net "MINI_RX_P_23")
			(options
				(clearance outline)
				(anchor circle)
			)
			(primitives
				(gr_poly
					(pts
						(arc
							(start 0.3048 0.2032)
							(mid 0.275042 0.275042)
							(end 0.2032 0.3048)
						)
						(arc
							(start -0.2032 0.3048)
							(mid -0.275042 0.275042)
							(end -0.3048 0.2032)
						)
						(arc
							(start -0.3048 -0.2032)
							(mid -0.275042 -0.275042)
							(end -0.2032 -0.3048)
						)
						(arc
							(start 0.2032 -0.3048)
							(mid 0.275042 -0.275042)
							(end 0.3048 -0.2032)
						)
					)
					(width 0)
					(fill yes)
				)
			)
		)
	)
	(footprint ""
		(layer "B.Cu")
		(at 290.449 -166.497)
		(property "Reference" "TP138"
			(at 0 0 0)
			(layer "B.SilkS")
			(hide yes)
			(effects
				(font
					(size 1.27 1.27)
				)
				(justify mirror)
			)
		)
		(property "Value" "TPAD28"
			(at -0.0127 -1.8034 0)
			(unlocked yes)
			(layer "B.Fab")
			(hide yes)
			(effects
				(font
					(size 1.016 1.016)
					(thickness 0.1524)
				)
				(justify mirror)
			)
		)
		(property "Device Type" "TPAD28"
			(at -0.0127 -3.3274 0)
			(unlocked yes)
			(layer "B.Fab")
			(hide yes)
			(effects
				(font
					(size 1.016 1.016)
					(thickness 0.1524)
				)
				(justify mirror)
			)
		)
		(duplicate_pad_numbers_are_jumpers no)
		(fp_poly
			(pts
				(arc
					(start 0.3556 0)
					(mid -0.3556 0)
					(end 0.3556 0)
				)
			)
			(stroke
				(width 0)
				(type default)
			)
			(fill no)
			(layer "B.CrtYd")
		)
		(fp_poly
			(pts
				(arc
					(start 0.6096 0)
					(mid -0.6096 0)
					(end 0.6096 0)
				)
			)
			(stroke
				(width 0)
				(type default)
			)
			(fill no)
			(layer "B.Fab")
		)
		(pad "1" smd circle
			(at 0 0 180)
			(size 0.7112 0.7112)
			(layers "B.Cu" "B.Mask" "B.Paste")
			(net "TP_BMC_GPIOE1")
		)
	)
	(footprint ""
		(layer "B.Cu")
		(at 116.821966 -32.639)
		(property "Reference" "STP137"
			(at 0 0 0)
			(layer "B.SilkS")
			(hide yes)
			(effects
				(font
					(size 1.27 1.27)
				)
				(justify mirror)
			)
		)
		(property "Value" "TPAD28"
			(at -0.0127 -1.8034 0)
			(unlocked yes)
			(layer "B.Fab")
			(hide yes)
			(effects
				(font
					(size 1.016 1.016)
					(thickness 0.1524)
				)
				(justify mirror)
			)
		)
		(property "Device Type" "TPAD28"
			(at -0.0127 -3.3274 0)
			(unlocked yes)
			(layer "B.Fab")
			(hide yes)
			(effects
				(font
					(size 1.016 1.016)
					(thickness 0.1524)
				)
				(justify mirror)
			)
		)
		(duplicate_pad_numbers_are_jumpers no)
		(fp_poly
			(pts
				(arc
					(start 0.3556 0)
					(mid -0.3556 0)
					(end 0.3556 0)
				)
			)
			(stroke
				(width 0)
				(type default)
			)
			(fill no)
			(layer "B.CrtYd")
		)
		(fp_poly
			(pts
				(arc
					(start 0.6096 0)
					(mid -0.6096 0)
					(end 0.6096 0)
				)
			)
			(stroke
				(width 0)
				(type default)
			)
			(fill no)
			(layer "B.Fab")
		)
		(pad "1" smd circle
			(at 0 0 180)
			(size 0.7112 0.7112)
			(layers "B.Cu" "B.Mask" "B.Paste")
			(net "IOC_GPIO_18")
		)
	)
	(footprint ""
		(layer "B.Cu")
		(at 318.008 -170.434 90)
		(property "Reference" "R301"
			(at 0 0 90)
			(layer "B.SilkS")
			(hide yes)
			(effects
				(font
					(size 1.27 1.27)
				)
				(justify mirror)
			)
		)
		(property "Value" "10KR2F-2-GP"
			(at -0.064008 -3.993896 90)
			(unlocked yes)
			(layer "B.Fab")
			(hide yes)
			(effects
				(font
					(size 1.016 1.016)
					(thickness 0.1524)
				)
				(justify mirror)
			)
		)
		(property "Device Type" "R402H16"
			(at -0.064008 -5.517896 90)
			(unlocked yes)
			(layer "B.Fab")
			(hide yes)
			(effects
				(font
					(size 1.016 1.016)
					(thickness 0.1524)
				)
				(justify mirror)
			)
		)
		(duplicate_pad_numbers_are_jumpers no)
		(fp_line
			(start 0.508 -0.9398)
			(end 0.508 0.9398)
			(stroke
				(width 0.1524)
				(type default)
			)
			(layer "B.SilkS")
		)
		(fp_line
			(start -0.508 -0.9398)
			(end 0.508 -0.9398)
			(stroke
				(width 0.1524)
				(type default)
			)
			(layer "B.SilkS")
		)
		(fp_rect
			(start 0.508 0.9398)
			(end -0.508 -0.9398)
			(stroke
				(width 0)
				(type default)
			)
			(fill no)
			(layer "B.CrtYd")
		)
		(fp_rect
			(start 0.508 0.9398)
			(end -0.508 -0.9398)
			(stroke
				(width 0)
				(type default)
			)
			(fill no)
			(layer "B.Fab")
		)
		(pad "1" smd custom
			(at 0 -0.4445 270)
			(size 0.1397 0.1397)
			(layers "B.Cu" "B.Mask" "B.Paste")
			(net "BMC0_ENTEST1")
			(options
				(clearance outline)
				(anchor circle)
			)
			(primitives
				(gr_poly
					(pts
						(arc
							(start -0.1778 0.2794)
							(mid -0.249642 0.249642)
							(end -0.2794 0.1778)
						)
						(arc
							(start -0.2794 -0.1778)
							(mid -0.249642 -0.249642)
							(end -0.1778 -0.2794)
						)
						(arc
							(start 0.1778 -0.2794)
							(mid 0.249642 -0.249642)
							(end 0.2794 -0.1778)
						)
						(arc
							(start 0.2794 0.1778)
							(mid 0.249642 0.249642)
							(end 0.1778 0.2794)
						)
					)
					(width 0)
					(fill yes)
				)
			)
		)
		(pad "2" smd custom
			(at 0 0.4445 270)
			(size 0.1397 0.1397)
			(layers "B.Cu" "B.Mask" "B.Paste")
			(net "GND")
			(options
				(clearance outline)
				(anchor circle)
			)
			(primitives
				(gr_poly
					(pts
						(arc
							(start -0.1778 0.2794)
							(mid -0.249642 0.249642)
							(end -0.2794 0.1778)
						)
						(arc
							(start -0.2794 -0.1778)
							(mid -0.249642 -0.249642)
							(end -0.1778 -0.2794)
						)
						(arc
							(start 0.1778 -0.2794)
							(mid 0.249642 -0.249642)
							(end 0.2794 -0.1778)
						)
						(arc
							(start 0.2794 0.1778)
							(mid 0.249642 0.249642)
							(end 0.1778 0.2794)
						)
					)
					(width 0)
					(fill yes)
				)
			)
		)
	)
	(footprint ""
		(layer "B.Cu")
		(at 113.29797 -94.615 90)
		(property "Reference" "SC1218"
			(at 0 0 90)
			(layer "B.SilkS")
			(hide yes)
			(effects
				(font
					(size 1.27 1.27)
				)
				(justify mirror)
			)
		)
		(property "Value" "SC1KP50V2KX-1GP"
			(at -1.1811 -2.7051 90)
			(unlocked yes)
			(layer "B.Fab")
			(hide yes)
			(effects
				(font
					(size 1.016 1.016)
					(thickness 0.1524)
				)
				(justify mirror)
			)
		)
		(property "Device Type" "C402H22"
			(at -1.1811 -4.2291 90)
			(unlocked yes)
			(layer "B.Fab")
			(hide yes)
			(effects
				(font
					(size 1.016 1.016)
					(thickness 0.1524)
				)
				(justify mirror)
			)
		)
		(duplicate_pad_numbers_are_jumpers no)
		(fp_rect
			(start 0.4318 0.9525)
			(end -0.4318 -0.9525)
			(stroke
				(width 0)
				(type default)
			)
			(fill no)
			(layer "B.CrtYd")
		)
		(fp_rect
			(start 0.4318 0.9525)
			(end -0.4318 -0.9525)
			(stroke
				(width 0)
				(type default)
			)
			(fill no)
			(layer "B.Fab")
		)
		(pad "1" smd custom
			(at 0 -0.4445 270)
			(size 0.1524 0.1524)
			(layers "B.Cu" "B.Mask" "B.Paste")
			(net "P0V9_E")
			(options
				(clearance outline)
				(anchor circle)
			)
			(primitives
				(gr_poly
					(pts
						(arc
							(start 0.3048 0.2032)
							(mid 0.275042 0.275042)
							(end 0.2032 0.3048)
						)
						(arc
							(start -0.2032 0.3048)
							(mid -0.275042 0.275042)
							(end -0.3048 0.2032)
						)
						(arc
							(start -0.3048 -0.2032)
							(mid -0.275042 -0.275042)
							(end -0.2032 -0.3048)
						)
						(arc
							(start 0.2032 -0.3048)
							(mid 0.275042 -0.275042)
							(end 0.3048 -0.2032)
						)
					)
					(width 0)
					(fill yes)
				)
			)
		)
		(pad "2" smd custom
			(at 0 0.4445 270)
			(size 0.1524 0.1524)
			(layers "B.Cu" "B.Mask" "B.Paste")
			(net "GND")
			(options
				(clearance outline)
				(anchor circle)
			)
			(primitives
				(gr_poly
					(pts
						(arc
							(start 0.3048 0.2032)
							(mid 0.275042 0.275042)
							(end 0.2032 0.3048)
						)
						(arc
							(start -0.2032 0.3048)
							(mid -0.275042 0.275042)
							(end -0.3048 0.2032)
						)
						(arc
							(start -0.3048 -0.2032)
							(mid -0.275042 -0.275042)
							(end -0.2032 -0.3048)
						)
						(arc
							(start 0.2032 -0.3048)
							(mid 0.275042 -0.275042)
							(end 0.3048 -0.2032)
						)
					)
					(width 0)
					(fill yes)
				)
			)
		)
	)
)
